FILE_TYPE = CONNECTIVITY;
{Allegro Design Entry HDL 17.2-2016 S081 (4005846) 1/11/2022}
"PAGE_NUMBER" = 319;
0"NC";
1"GND\g";
2"GND\g";
3"P5E_CPU1_PE3_TX_C_DP<1>";
4"P5E_CPU1_PE2_RX_DN<1>";
5"P5E_CPU1_PE2_RX_DP<1>";
6"P5E_CPU1_PE3_RX_DP<1>";
7"P5E_CPU1_PE3_RX_DN<1>";
8"SMB_BMC_SWB_BUF_SDA";
9"PRSNT_CABLE_GPU_B3_N";
10"P5E_CPU1_PE2_TX_C_DN<0>";
11"P5E_CPU1_PE3_TX_C_DN<1>";
12"P5E_CPU1_PE2_TX_C_DP<1>";
13"P5E_CPU1_PE2_TX_C_DN<1>";
14"P5E_CPU1_PE3_RX_DN<2>";
15"P5E_CPU1_PE3_RX_DP<2>";
16"P5E_CPU1_PE2_RX_DP<2>";
17"P5E_CPU1_PE2_RX_DN<2>";
18"P5E_CPU1_PE3_TX_C_DN<2>";
19"P5E_CPU1_PE3_TX_C_DP<2>";
20"P5E_CPU1_PE2_TX_C_DN<2>";
21"SMB_BMC_SWB_BUF_SCL";
22"P5E_CPU1_PE3_TX_C_DP<5>";
23"P5E_CPU1_PE2_RX_DN<5>";
24"P5E_CPU1_PE3_RX_DN<5>";
25"P5E_CPU1_PE3_RX_DP<5>";
26"BIC_MONITER";
27"GPU_3V3IO_RSVD0_FFU";
28"GPU_3V3IO_RSVD1_FFU";
29"P5E_CPU1_PE2_TX_C_DP<2>";
30"P5E_CPU1_PE3_RX_DP<0>";
31"P5E_CPU1_PE3_TX_C_DN<0>";
32"P5E_CPU1_PE2_RX_DP<0>";
33"P5E_CPU1_PE2_RX_DN<0>";
34"P5E_CPU1_PE2_TX_C_DP<0>";
35"P5E_CPU1_PE3_TX_C_DP<0>";
36"P5E_CPU1_PE3_RX_DN<0>";
37"P5E_CPU1_PE3_RX_DP<3>";
38"P5E_CPU1_PE2_RX_DP<3>";
39"P5E_CPU1_PE2_RX_DN<3>";
40"P5E_CPU1_PE3_TX_C_DN<3>";
41"P5E_CPU1_PE2_TX_C_DN<3>";
42"P5E_CPU1_PE3_TX_C_DP<3>";
43"P5E_CPU1_PE3_RX_DN<3>";
44"P5E_CPU1_PE3_TX_C_DP<6>";
45"P5E_CPU1_PE2_TX_C_DP<6>";
46"P5E_CPU1_PE2_TX_C_DN<6>";
47"GPU_FPGA_EROT_FATALERR_N";
48"P5E_CPU1_PE3_TX_C_DN<6>";
49"P5E_CPU1_PE2_RX_DN<6>";
50"P5E_CPU1_PE2_RX_DP<6>";
51"P5E_CPU1_PE3_TX_C_DN<4>";
52"P5E_CPU1_PE3_TX_C_DP<4>";
53"P5E_CPU1_PE2_TX_C_DN<4>";
54"P5E_CPU1_PE2_TX_C_DP<5>";
55"P5E_CPU1_PE2_TX_C_DN<5>";
56"P5E_CPU1_PE3_TX_C_DN<5>";
57"P5E_CPU1_PE2_RX_DP<5>";
58"P5E_CPU1_PE2_RX_DP<7>";
59"P5E_CPU1_PE2_RX_DN<7>";
60"P5E_CPU1_PE3_TX_C_DP<7>";
61"P5E_CPU1_PE2_TX_C_DP<7>";
62"P5E_CPU1_PE2_TX_C_DN<7>";
63"P5E_CPU1_PE3_RX_DN<7>";
64"BMC_MONITER_BUF";
65"P5E_CPU1_PE3_RX_DN<6>";
66"P5E_CPU1_PE3_TX_C_DN<7>";
67"P5E_CPU1_PE3_RX_DP<7>";
68"P5E_CPU1_PE3_RX_DP<6>";
69"P5E_CPU1_PE2_TX_C_DP<4>";
70"P5E_CPU1_PE2_RX_DN<4>";
71"P5E_CPU1_PE2_RX_DP<4>";
72"P5E_CPU1_PE3_RX_DN<4>";
73"P5E_CPU1_PE3_RX_DP<4>";
74"P5E_CPU1_PE2_TX_C_DP<3>";
%"UNIVERSAL_GND"
"1","(-2275,-1475)","0","logical_power","I15";
;
HDL_POWER"GND"
CDS_LIB"logical_power";
"A"2;
%"UNIVERSAL_GND"
"1","(2450,-1600)","0","logical_power","I52";
;
CDS_LIB"logical_power"
HDL_POWER"GND";
"A"1;
%"CONN112_10137002101LF"
"2","(3600,350)","0","pure_quanta","I53";
;
PART_NUMBER"DFHSB2FR012"
PART_TYPE"THLF"
MATERIAL"IO"
LOCATION"J109"
CDS_LIB"pure_quanta"
CDS_LMAN_SYM_OUTLINE"-775,1650,775,-1650"
VALUE"CONN112_10137002-101LF"
NEEDS_NO_SIZE"TRUE"
$SEC"2"
CDS_SEC"2";
"N4"
$PN"N4"27;
"M4"
$PN"M4"1;
"N3"
$PN"N3"1;
"M3"
$PN"M3"55;
"N2"
$PN"N2"47;
"M2"
$PN"M2"1;
"N1"
$PN"N1"1;
"M1"
$PN"M1"62;
"L1"
$PN"L1"61;
"L2"
$PN"L2"46;
"L3"
$PN"L3"54;
"L4"
$PN"L4"53;
"K1"
$PN"K1"1;
"K2"
$PN"K2"45;
"K3"
$PN"K3"1;
"K4"
$PN"K4"69;
"J1"
$PN"J1"60;
"J2"
$PN"J2"1;
"J3"
$PN"J3"22;
"J4"
$PN"J4"1;
"I1"
$PN"I1"66;
"I2"
$PN"I2"44;
"I3"
$PN"I3"56;
"I4"
$PN"I4"52;
"H1"
$PN"H1"1;
"H2"
$PN"H2"48;
"H3"
$PN"H3"1;
"H4"
$PN"H4"51;
"G1"
$PN"G1"59;
"G2"
$PN"G2"1;
"G3"
$PN"G3"23;
"G4"
$PN"G4"1;
"F1"
$PN"F1"58;
"F2"
$PN"F2"49;
"F3"
$PN"F3"57;
"F4"
$PN"F4"70;
"E1"
$PN"E1"1;
"E2"
$PN"E2"50;
"E3"
$PN"E3"1;
"E4"
$PN"E4"71;
"D1"
$PN"D1"63;
"D2"
$PN"D2"1;
"D3"
$PN"D3"24;
"D4"
$PN"D4"1;
"C1"
$PN"C1"67;
"C2"
$PN"C2"65;
"C3"
$PN"C3"25;
"C4"
$PN"C4"72;
"B1"
$PN"B1"1;
"B2"
$PN"B2"68;
"B3"
$PN"B3"1;
"B4"
$PN"B4"73;
"A1"
$PN"A1"64;
"A2"
$PN"A2"1;
"A3"
$PN"A3"26;
"A4"
$PN"A4"1;
%"CONN112_10137002101LF"
"1","(-1175,425)","0","pure_quanta","I76";
;
PART_NUMBER"DFHSB2FR012"
PART_TYPE"THLF"
MATERIAL"IO"
LOCATION"J109"
VALUE"CONN112_10137002-101LF"
NEEDS_NO_SIZE"TRUE"
CDS_LMAN_SYM_OUTLINE"-775,1650,775,-1650"
CDS_LIB"pure_quanta"
$SEC"1"
CDS_SEC"1";
"N8"
$PN"N8"9;
"M8"
$PN"M8"2;
"N7"
$PN"N7"2;
"M7"
$PN"M7"13;
"N6"
$PN"N6"28;
"M6"
$PN"M6"2;
"N5"
$PN"N5"2;
"M5"
$PN"M5"41;
"L5"
$PN"L5"74;
"L6"
$PN"L6"20;
"L7"
$PN"L7"12;
"L8"
$PN"L8"10;
"K5"
$PN"K5"2;
"K6"
$PN"K6"29;
"K7"
$PN"K7"2;
"K8"
$PN"K8"34;
"J5"
$PN"J5"42;
"J6"
$PN"J6"2;
"J7"
$PN"J7"3;
"J8"
$PN"J8"2;
"I5"
$PN"I5"40;
"I6"
$PN"I6"19;
"I7"
$PN"I7"11;
"I8"
$PN"I8"31;
"H5"
$PN"H5"2;
"H6"
$PN"H6"18;
"H7"
$PN"H7"2;
"H8"
$PN"H8"35;
"G5"
$PN"G5"39;
"G6"
$PN"G6"2;
"G7"
$PN"G7"4;
"G8"
$PN"G8"2;
"F5"
$PN"F5"38;
"F6"
$PN"F6"17;
"F7"
$PN"F7"5;
"F8"
$PN"F8"33;
"E5"
$PN"E5"2;
"E6"
$PN"E6"16;
"E7"
$PN"E7"2;
"E8"
$PN"E8"32;
"D5"
$PN"D5"37;
"D6"
$PN"D6"2;
"D7"
$PN"D7"6;
"D8"
$PN"D8"2;
"C5"
$PN"C5"43;
"C6"
$PN"C6"15;
"C7"
$PN"C7"7;
"C8"
$PN"C8"36;
"B5"
$PN"B5"2;
"B6"
$PN"B6"14;
"B7"
$PN"B7"2;
"B8"
$PN"B8"30;
"A5"
$PN"A5"21;
"A6"
$PN"A6"2;
"A7"
$PN"A7"8;
"A8"
$PN"A8"2;
END.
